(kicad_pcb
	(version 20260206)
	(generator "pcbnew")
	(generator_version "10.0")
	(general
		(thickness 1.6)
		(legacy_teardrops no)
	)
	(paper "A4")
	(title_block
		(title "timecard-production-celestica-r4006 — R4006-B0001-02_R01.brd")
		(comment 1 "Time Appliance Project (Time Card) / footprints 925-929 of 1113")
	)
	(layers
		(0 "F.Cu" signal "TOP")
		(4 "In1.Cu" signal "L02_GND1")
		(6 "In2.Cu" signal "L03_SIG1")
		(8 "In3.Cu" signal "L04_GND2")
		(10 "In4.Cu" signal "L05_VCC1")
		(12 "In5.Cu" signal "L06_VCC2")
		(14 "In6.Cu" signal "L07_GND3")
		(16 "In7.Cu" signal "L08_SIG2")
		(18 "In8.Cu" signal "L09_GND4")
		(2 "B.Cu" signal "BOTTOM")
		(9 "F.Adhes" user "F.Adhesive")
		(11 "B.Adhes" user "B.Adhesive")
		(13 "F.Paste" user "Package Geometry/Pastemask Top")
		(15 "B.Paste" user "Package Geometry/Pastemask Bottom")
		(5 "F.SilkS" user "Ref Des/Silkscreen Top")
		(7 "B.SilkS" user "Ref Des/Silkscreen Bottom")
		(1 "F.Mask" user "Board Geometry/Soldermask Top")
		(3 "B.Mask" user "Board Geometry/Soldermask Bottom")
		(17 "Dwgs.User" user "User.Drawings")
		(19 "Cmts.User" user "User.Comments")
		(21 "Eco1.User" user "User.Eco1")
		(23 "Eco2.User" user "User.Eco2")
		(25 "Edge.Cuts" user "Board Geometry/Outline")
		(27 "Margin" user)
		(31 "F.CrtYd" user "Package Geometry/Place Bound Top")
		(29 "B.CrtYd" user "Package Geometry/Place Bound Bottom")
		(35 "F.Fab" user "Ref Des/Assembly Top")
		(33 "B.Fab" user "Ref Des/Assembly Bottom")
	)
	(footprint ""
		(layer "B.Cu")
		(at 26.416 -91.059 90)
		(property "Reference" "R460"
			(at 2.286 -5.11937 270)
			(unlocked yes)
			(layer "B.SilkS")
			(effects
				(font
					(size 0.7874 0.5842)
					(thickness 0.1524)
				)
				(justify mirror)
			)
		)
		(property "Value" "VAL*"
			(at -0.02032 2.13233 90)
			(unlocked yes)
			(layer "B.Fab")
			(hide yes)
			(effects
				(font
					(size 0.7874 0.5842)
					(thickness 0.1524)
				)
				(justify mirror)
			)
		)
		(property "Tolerance" "TOL*"
			(at -0.044704 3.05435 90)
			(unlocked yes)
			(layer "Cmts.User")
			(hide yes)
			(effects
				(font
					(size 0.7874 0.5842)
					(thickness 0.1524)
				)
				(justify mirror)
			)
		)
		(property "User Part Number" "PARTNUM*"
			(at -0.02032 4.024884 90)
			(unlocked yes)
			(layer "Cmts.User")
			(hide yes)
			(effects
				(font
					(size 0.7874 0.5842)
					(thickness 0.1524)
				)
				(justify mirror)
			)
		)
		(property "Device Type" "RESISTOR-G155-11001-01,1KOHM,1%"
			(at -0.008382 1.210564 90)
			(unlocked yes)
			(layer "B.Fab")
			(hide yes)
			(effects
				(font
					(size 0.7874 0.5842)
					(thickness 0.1524)
				)
				(justify mirror)
			)
		)
		(duplicate_pad_numbers_are_jumpers no)
		(fp_line
			(start 1.143 -0.5588)
			(end 1.143 0.5588)
			(stroke
				(width 0.1)
				(type default)
			)
			(layer "B.SilkS")
		)
		(fp_line
			(start -1.143 -0.5588)
			(end 1.143 -0.5588)
			(stroke
				(width 0.1)
				(type default)
			)
			(layer "B.SilkS")
		)
		(fp_line
			(start 1.143 0.5588)
			(end -1.143 0.5588)
			(stroke
				(width 0.1)
				(type default)
			)
			(layer "B.SilkS")
		)
		(fp_line
			(start -1.143 0.5588)
			(end -1.143 -0.5588)
			(stroke
				(width 0.1)
				(type default)
			)
			(layer "B.SilkS")
		)
		(fp_poly
			(pts
				(xy 1.143 0.5588) (xy -1.143 0.5588) (xy -1.143 -0.5588) (xy 1.143 -0.5588)
			)
			(stroke
				(width 0)
				(type default)
			)
			(fill no)
			(layer "B.CrtYd")
		)
		(fp_line
			(start 0.508 -0.3048)
			(end 0.508 0.3048)
			(stroke
				(width 0.1)
				(type default)
			)
			(layer "B.Fab")
		)
		(fp_line
			(start -0.508 -0.3048)
			(end 0.508 -0.3048)
			(stroke
				(width 0.1)
				(type default)
			)
			(layer "B.Fab")
		)
		(fp_line
			(start 0.508 0.3048)
			(end -0.508 0.3048)
			(stroke
				(width 0.1)
				(type default)
			)
			(layer "B.Fab")
		)
		(fp_line
			(start -0.508 0.3048)
			(end -0.508 -0.3048)
			(stroke
				(width 0.1)
				(type default)
			)
			(layer "B.Fab")
		)
		(pad "1" smd rect
			(at 0.5334 0 270)
			(size 0.7112 0.6096)
			(layers "B.Cu" "B.Mask" "B.Paste")
			(net "FT_USB_DETECT")
		)
		(pad "2" smd rect
			(at -0.5334 0 270)
			(size 0.7112 0.6096)
			(layers "B.Cu" "B.Mask" "B.Paste")
			(net "UNNAMED_524_FT4232HLREELQFP64_7")
		)
		(zone
			(layer "B.Cu")
			(hatch none 0.5)
			(connect_pads
				(clearance 0)
			)
			(min_thickness 0.25)
			(keepout
				(tracks allowed)
				(vias not_allowed)
				(pads allowed)
				(copperpour not_allowed)
				(footprints allowed)
			)
			(placement
				(enabled no)
				(sheetname "")
			)
			(fill
				(thermal_gap 0.5)
				(thermal_bridge_width 0.5)
				(island_removal_mode 0)
			)
			(polygon
				(pts
					(xy 26.7208 -91.1352) (xy 26.1112 -91.1352) (xy 26.1112 -90.9828) (xy 26.7208 -90.9828)
				)
			)
		)
		(zone
			(layer "B.Cu")
			(hatch none 0.5)
			(connect_pads
				(clearance 0)
			)
			(min_thickness 0.25)
			(keepout
				(tracks not_allowed)
				(vias allowed)
				(pads allowed)
				(copperpour not_allowed)
				(footprints allowed)
			)
			(placement
				(enabled no)
				(sheetname "")
			)
			(fill
				(thermal_gap 0.5)
				(thermal_bridge_width 0.5)
				(island_removal_mode 0)
			)
			(polygon
				(pts
					(xy 26.7208 -91.1352) (xy 26.1112 -91.1352) (xy 26.1112 -90.9828) (xy 26.7208 -90.9828)
				)
			)
		)
	)
	(footprint ""
		(layer "B.Cu")
		(at 110.363 -75.565 180)
		(property "Reference" "R295"
			(at 2.032 1.35763 0)
			(unlocked yes)
			(layer "B.SilkS")
			(effects
				(font
					(size 0.7874 0.5842)
					(thickness 0.1524)
				)
				(justify mirror)
			)
		)
		(property "Value" "VAL*"
			(at -0.02032 2.13233 180)
			(unlocked yes)
			(layer "B.Fab")
			(hide yes)
			(effects
				(font
					(size 0.7874 0.5842)
					(thickness 0.1524)
				)
				(justify mirror)
			)
		)
		(property "Tolerance" "TOL*"
			(at -0.044704 3.05435 180)
			(unlocked yes)
			(layer "Cmts.User")
			(hide yes)
			(effects
				(font
					(size 0.7874 0.5842)
					(thickness 0.1524)
				)
				(justify mirror)
			)
		)
		(property "User Part Number" "PARTNUM*"
			(at -0.02032 4.024884 180)
			(unlocked yes)
			(layer "Cmts.User")
			(hide yes)
			(effects
				(font
					(size 0.7874 0.5842)
					(thickness 0.1524)
				)
				(justify mirror)
			)
		)
		(property "Device Type" "RESISTOR-G155-11002-01,10KOHM,A"
			(at -0.008382 1.210564 180)
			(unlocked yes)
			(layer "B.Fab")
			(hide yes)
			(effects
				(font
					(size 0.7874 0.5842)
					(thickness 0.1524)
				)
				(justify mirror)
			)
		)
		(duplicate_pad_numbers_are_jumpers no)
		(fp_line
			(start 1.143 0.5588)
			(end -1.143 0.5588)
			(stroke
				(width 0.1)
				(type default)
			)
			(layer "B.SilkS")
		)
		(fp_line
			(start 1.143 -0.5588)
			(end 1.143 0.5588)
			(stroke
				(width 0.1)
				(type default)
			)
			(layer "B.SilkS")
		)
		(fp_line
			(start -1.143 0.5588)
			(end -1.143 -0.5588)
			(stroke
				(width 0.1)
				(type default)
			)
			(layer "B.SilkS")
		)
		(fp_line
			(start -1.143 -0.5588)
			(end 1.143 -0.5588)
			(stroke
				(width 0.1)
				(type default)
			)
			(layer "B.SilkS")
		)
		(fp_poly
			(pts
				(xy 1.143 0.5588) (xy -1.143 0.5588) (xy -1.143 -0.5588) (xy 1.143 -0.5588)
			)
			(stroke
				(width 0)
				(type default)
			)
			(fill no)
			(layer "B.CrtYd")
		)
		(fp_line
			(start 0.508 0.3048)
			(end -0.508 0.3048)
			(stroke
				(width 0.1)
				(type default)
			)
			(layer "B.Fab")
		)
		(fp_line
			(start 0.508 -0.3048)
			(end 0.508 0.3048)
			(stroke
				(width 0.1)
				(type default)
			)
			(layer "B.Fab")
		)
		(fp_line
			(start -0.508 0.3048)
			(end -0.508 -0.3048)
			(stroke
				(width 0.1)
				(type default)
			)
			(layer "B.Fab")
		)
		(fp_line
			(start -0.508 -0.3048)
			(end 0.508 -0.3048)
			(stroke
				(width 0.1)
				(type default)
			)
			(layer "B.Fab")
		)
		(pad "1" smd rect
			(at 0.5334 0)
			(size 0.7112 0.6096)
			(layers "B.Cu" "B.Mask" "B.Paste")
			(net "XP3R3V_FPGA")
		)
		(pad "2" smd rect
			(at -0.5334 0)
			(size 0.7112 0.6096)
			(layers "B.Cu" "B.Mask" "B.Paste")
			(net "UNNAMED_515_NCP45560IMNTWGHDFN1")
		)
		(zone
			(layer "B.Cu")
			(hatch none 0.5)
			(connect_pads
				(clearance 0)
			)
			(min_thickness 0.25)
			(keepout
				(tracks allowed)
				(vias not_allowed)
				(pads allowed)
				(copperpour not_allowed)
				(footprints allowed)
			)
			(placement
				(enabled no)
				(sheetname "")
			)
			(fill
				(thermal_gap 0.5)
				(thermal_bridge_width 0.5)
				(island_removal_mode 0)
			)
			(polygon
				(pts
					(xy 110.2868 -75.8698) (xy 110.2868 -75.2602) (xy 110.4392 -75.2602) (xy 110.4392 -75.8698)
				)
			)
		)
		(zone
			(layer "B.Cu")
			(hatch none 0.5)
			(connect_pads
				(clearance 0)
			)
			(min_thickness 0.25)
			(keepout
				(tracks not_allowed)
				(vias allowed)
				(pads allowed)
				(copperpour not_allowed)
				(footprints allowed)
			)
			(placement
				(enabled no)
				(sheetname "")
			)
			(fill
				(thermal_gap 0.5)
				(thermal_bridge_width 0.5)
				(island_removal_mode 0)
			)
			(polygon
				(pts
					(xy 110.2868 -75.8698) (xy 110.2868 -75.2602) (xy 110.4392 -75.2602) (xy 110.4392 -75.8698)
				)
			)
		)
	)
	(footprint ""
		(layer "B.Cu")
		(at 124.079 -89.535 -90)
		(property "Reference" "R111"
			(at -3.683 -0.08763 270)
			(unlocked yes)
			(layer "B.SilkS")
			(effects
				(font
					(size 0.7874 0.5842)
					(thickness 0.1524)
				)
				(justify mirror)
			)
		)
		(property "Value" "VAL*"
			(at -0.02032 2.13233 270)
			(unlocked yes)
			(layer "B.Fab")
			(hide yes)
			(effects
				(font
					(size 0.7874 0.5842)
					(thickness 0.1524)
				)
				(justify mirror)
			)
		)
		(property "Tolerance" "TOL*"
			(at -0.044704 3.05435 270)
			(unlocked yes)
			(layer "Cmts.User")
			(hide yes)
			(effects
				(font
					(size 0.7874 0.5842)
					(thickness 0.1524)
				)
				(justify mirror)
			)
		)
		(property "User Part Number" "PARTNUM*"
			(at -0.02032 4.024884 270)
			(unlocked yes)
			(layer "Cmts.User")
			(hide yes)
			(effects
				(font
					(size 0.7874 0.5842)
					(thickness 0.1524)
				)
				(justify mirror)
			)
		)
		(property "Device Type" "RESISTOR-G155-133R0-01,33OHM,1%"
			(at -0.008382 1.210564 270)
			(unlocked yes)
			(layer "B.Fab")
			(hide yes)
			(effects
				(font
					(size 0.7874 0.5842)
					(thickness 0.1524)
				)
				(justify mirror)
			)
		)
		(duplicate_pad_numbers_are_jumpers no)
		(fp_line
			(start -1.143 0.5588)
			(end -1.143 -0.5588)
			(stroke
				(width 0.1)
				(type default)
			)
			(layer "B.SilkS")
		)
		(fp_line
			(start 1.143 0.5588)
			(end -1.143 0.5588)
			(stroke
				(width 0.1)
				(type default)
			)
			(layer "B.SilkS")
		)
		(fp_line
			(start -1.143 -0.5588)
			(end 1.143 -0.5588)
			(stroke
				(width 0.1)
				(type default)
			)
			(layer "B.SilkS")
		)
		(fp_line
			(start 1.143 -0.5588)
			(end 1.143 0.5588)
			(stroke
				(width 0.1)
				(type default)
			)
			(layer "B.SilkS")
		)
		(fp_rect
			(start 1.143 0.5588)
			(end -1.143 -0.5588)
			(stroke
				(width 0)
				(type default)
			)
			(fill no)
			(layer "B.CrtYd")
		)
		(fp_line
			(start -0.508 0.3048)
			(end -0.508 -0.3048)
			(stroke
				(width 0.1)
				(type default)
			)
			(layer "B.Fab")
		)
		(fp_line
			(start 0.508 0.3048)
			(end -0.508 0.3048)
			(stroke
				(width 0.1)
				(type default)
			)
			(layer "B.Fab")
		)
		(fp_line
			(start -0.508 -0.3048)
			(end 0.508 -0.3048)
			(stroke
				(width 0.1)
				(type default)
			)
			(layer "B.Fab")
		)
		(fp_line
			(start 0.508 -0.3048)
			(end 0.508 0.3048)
			(stroke
				(width 0.1)
				(type default)
			)
			(layer "B.Fab")
		)
		(pad "1" smd rect
			(at 0.5334 0 90)
			(size 0.7112 0.6096)
			(layers "B.Cu" "B.Mask" "B.Paste")
			(net "FPGA_IN_GPSTP2_OUT")
		)
		(pad "2" smd rect
			(at -0.5334 0 90)
			(size 0.7112 0.6096)
			(layers "B.Cu" "B.Mask" "B.Paste")
			(net "GPSTP2_OUT")
		)
		(zone
			(layer "B.Cu")
			(hatch none 0.5)
			(connect_pads
				(clearance 0)
			)
			(min_thickness 0.25)
			(keepout
				(tracks allowed)
				(vias not_allowed)
				(pads allowed)
				(copperpour not_allowed)
				(footprints allowed)
			)
			(placement
				(enabled no)
				(sheetname "")
			)
			(fill
				(thermal_gap 0.5)
				(thermal_bridge_width 0.5)
				(island_removal_mode 0)
			)
			(polygon
				(pts
					(xy 123.7742 -89.4588) (xy 124.3838 -89.4588) (xy 124.3838 -89.6112) (xy 123.7742 -89.6112)
				)
			)
		)
	)
	(footprint ""
		(layer "B.Cu")
		(at 100.347018 -50.823114)
		(property "Reference" "C211"
			(at -1.287018 1.070864 0)
			(unlocked yes)
			(layer "B.SilkS")
			(effects
				(font
					(size 0.635 0.4064)
					(thickness 0.1524)
				)
				(justify mirror)
			)
		)
		(property "Value" "VAL*"
			(at 0 3.718306 0)
			(unlocked yes)
			(layer "B.Fab")
			(hide yes)
			(effects
				(font
					(size 0.7874 0.5842)
					(thickness 0.127)
				)
				(justify mirror)
			)
		)
		(property "Device Type" "CAPACITOR-G105-0B104-CK,0.1UF,A"
			(at 0 1.432306 0)
			(unlocked yes)
			(layer "B.Fab")
			(hide yes)
			(effects
				(font
					(size 0.7874 0.5842)
					(thickness 0.127)
				)
				(justify mirror)
			)
		)
		(property "User Part Number" "PARTNUM*"
			(at 0 2.575306 0)
			(unlocked yes)
			(layer "Cmts.User")
			(hide yes)
			(effects
				(font
					(size 0.7874 0.5842)
					(thickness 0.127)
				)
				(justify mirror)
			)
		)
		(property "Tolerance" "TOL*"
			(at 0 4.861306 0)
			(unlocked yes)
			(layer "Cmts.User")
			(hide yes)
			(effects
				(font
					(size 0.7874 0.5842)
					(thickness 0.127)
				)
				(justify mirror)
			)
		)
		(duplicate_pad_numbers_are_jumpers no)
		(fp_line
			(start -0.970026 -0.4699)
			(end -0.970026 0.4699)
			(stroke
				(width 0.1)
				(type default)
			)
			(layer "B.SilkS")
		)
		(fp_line
			(start -0.970026 0.4699)
			(end 0.970026 0.4699)
			(stroke
				(width 0.1)
				(type default)
			)
			(layer "B.SilkS")
		)
		(fp_line
			(start 0.970026 -0.4699)
			(end -0.970026 -0.4699)
			(stroke
				(width 0.1)
				(type default)
			)
			(layer "B.SilkS")
		)
		(fp_line
			(start 0.970026 0.4699)
			(end 0.970026 -0.4699)
			(stroke
				(width 0.1)
				(type default)
			)
			(layer "B.SilkS")
		)
		(fp_poly
			(pts
				(xy 0.970026 0.4699) (xy -0.970026 0.4699) (xy -0.970026 -0.4699) (xy 0.970026 -0.4699)
			)
			(stroke
				(width 0)
				(type default)
			)
			(fill no)
			(layer "B.CrtYd")
		)
		(fp_line
			(start -0.508 -0.3048)
			(end -0.508 0.3048)
			(stroke
				(width 0.1)
				(type default)
			)
			(layer "B.Fab")
		)
		(fp_line
			(start -0.508 0.3048)
			(end 0.508 0.3048)
			(stroke
				(width 0.1)
				(type default)
			)
			(layer "B.Fab")
		)
		(fp_line
			(start 0.508 -0.3048)
			(end -0.508 -0.3048)
			(stroke
				(width 0.1)
				(type default)
			)
			(layer "B.Fab")
		)
		(fp_line
			(start 0.508 0.3048)
			(end 0.508 -0.3048)
			(stroke
				(width 0.1)
				(type default)
			)
			(layer "B.Fab")
		)
		(pad "1" smd circle
			(at 0.500126 0 180)
			(size 0.635 0.635)
			(layers "B.Cu" "B.Mask" "B.Paste")
			(net "XP3R3V_FPGA")
		)
		(pad "2" smd circle
			(at -0.500126 0 180)
			(size 0.635 0.635)
			(layers "B.Cu" "B.Mask" "B.Paste")
			(net "SG")
		)
	)
	(footprint ""
		(layer "B.Cu")
		(at 101.4476 -83.5914 180)
		(property "Reference" "R457"
			(at -0.1524 1.07823 0)
			(unlocked yes)
			(layer "B.SilkS")
			(effects
				(font
					(size 0.7874 0.5842)
					(thickness 0.1524)
				)
				(justify mirror)
			)
		)
		(property "Value" "VAL*"
			(at -0.02032 2.13233 180)
			(unlocked yes)
			(layer "B.Fab")
			(hide yes)
			(effects
				(font
					(size 0.7874 0.5842)
					(thickness 0.1524)
				)
				(justify mirror)
			)
		)
		(property "Tolerance" "TOL*"
			(at -0.044704 3.05435 180)
			(unlocked yes)
			(layer "Cmts.User")
			(hide yes)
			(effects
				(font
					(size 0.7874 0.5842)
					(thickness 0.1524)
				)
				(justify mirror)
			)
		)
		(property "User Part Number" "PARTNUM*"
			(at -0.02032 4.024884 180)
			(unlocked yes)
			(layer "Cmts.User")
			(hide yes)
			(effects
				(font
					(size 0.7874 0.5842)
					(thickness 0.1524)
				)
				(justify mirror)
			)
		)
		(property "Device Type" "RESISTOR-G155-14701-01,4.7KOHMA"
			(at -0.008382 1.210564 180)
			(unlocked yes)
			(layer "B.Fab")
			(hide yes)
			(effects
				(font
					(size 0.7874 0.5842)
					(thickness 0.1524)
				)
				(justify mirror)
			)
		)
		(duplicate_pad_numbers_are_jumpers no)
		(fp_line
			(start 1.143 0.5588)
			(end -1.143 0.5588)
			(stroke
				(width 0.1)
				(type default)
			)
			(layer "B.SilkS")
		)
		(fp_line
			(start 1.143 -0.5588)
			(end 1.143 0.5588)
			(stroke
				(width 0.1)
				(type default)
			)
			(layer "B.SilkS")
		)
		(fp_line
			(start -1.143 0.5588)
			(end -1.143 -0.5588)
			(stroke
				(width 0.1)
				(type default)
			)
			(layer "B.SilkS")
		)
		(fp_line
			(start -1.143 -0.5588)
			(end 1.143 -0.5588)
			(stroke
				(width 0.1)
				(type default)
			)
			(layer "B.SilkS")
		)
		(fp_poly
			(pts
				(xy 1.143 0.5588) (xy -1.143 0.5588) (xy -1.143 -0.5588) (xy 1.143 -0.5588)
			)
			(stroke
				(width 0)
				(type default)
			)
			(fill no)
			(layer "B.CrtYd")
		)
		(fp_line
			(start 0.508 0.3048)
			(end -0.508 0.3048)
			(stroke
				(width 0.1)
				(type default)
			)
			(layer "B.Fab")
		)
		(fp_line
			(start 0.508 -0.3048)
			(end 0.508 0.3048)
			(stroke
				(width 0.1)
				(type default)
			)
			(layer "B.Fab")
		)
		(fp_line
			(start -0.508 0.3048)
			(end -0.508 -0.3048)
			(stroke
				(width 0.1)
				(type default)
			)
			(layer "B.Fab")
		)
		(fp_line
			(start -0.508 -0.3048)
			(end 0.508 -0.3048)
			(stroke
				(width 0.1)
				(type default)
			)
			(layer "B.Fab")
		)
		(pad "1" smd rect
			(at 0.5334 0)
			(size 0.7112 0.6096)
			(layers "B.Cu" "B.Mask" "B.Paste")
			(net "XP3R3V_FPGA")
		)
		(pad "2" smd rect
			(at -0.5334 0)
			(size 0.7112 0.6096)
			(layers "B.Cu" "B.Mask" "B.Paste")
			(net "MUX2_SEL")
		)
		(zone
			(layer "B.Cu")
			(hatch none 0.5)
			(connect_pads
				(clearance 0)
			)
			(min_thickness 0.25)
			(keepout
				(tracks not_allowed)
				(vias allowed)
				(pads allowed)
				(copperpour not_allowed)
				(footprints allowed)
			)
			(placement
				(enabled no)
				(sheetname "")
			)
			(fill
				(thermal_gap 0.5)
				(thermal_bridge_width 0.5)
				(island_removal_mode 0)
			)
			(polygon
				(pts
					(xy 101.3714 -83.8962) (xy 101.3714 -83.2866) (xy 101.5238 -83.2866) (xy 101.5238 -83.8962)
				)
			)
		)
		(zone
			(layer "B.Cu")
			(hatch none 0.5)
			(connect_pads
				(clearance 0)
			)
			(min_thickness 0.25)
			(keepout
				(tracks allowed)
				(vias not_allowed)
				(pads allowed)
				(copperpour not_allowed)
				(footprints allowed)
			)
			(placement
				(enabled no)
				(sheetname "")
			)
			(fill
				(thermal_gap 0.5)
				(thermal_bridge_width 0.5)
				(island_removal_mode 0)
			)
			(polygon
				(pts
					(xy 101.3714 -83.8962) (xy 101.3714 -83.2866) (xy 101.5238 -83.2866) (xy 101.5238 -83.8962)
				)
			)
		)
	)
)
